# S9S_MB_2U (Grand Teton) — schematic netlist excerpt (pin names and nets, part order shuffled) for the footprints in the layout excerpt that follows; sources: Cadence DE-HDL packaged netlist, KiCad conversion of 03242023_DA0F0TMBIJ0_F0T_Motherboard_J_brd_V01_OCP.brd

R4703  Q_RES  560 1% CHIP  pkg 0402LF  page 255 : A = LED_P12V_PSU_R1 ; B = LED_P12V_PSU_R2
R2348  Q_RES  0 5% CHIP  pkg 0402LF  page 215 : A = FM_DEBUG_PORT_PRSNT_N ; B = FM_DEBUG_PORT_PRSNT_R_N
PC240_P0_8  Q_CAP  22UF 16V 20% X6S  pkg C0805  page 270 : A = SW_P12V_PVCCIN_CPU0_FLT ; B = GND

(kicad_pcb
	(version 20260206)
	(generator "pcbnew")
	(generator_version "10.0")
	(general
		(thickness 1.6)
		(legacy_teardrops no)
	)
	(paper "A4")
	(title_block
		(title "03242023_DA0F0TMBIJ0_F0T_Motherboard_J_brd_V01_OCP.brd")
		(comment 1 "Grand Teton / footprints 4678-4680 of 6105")
	)
	(layers
		(0 "F.Cu" signal "TOP")
		(4 "In1.Cu" signal "GND")
		(6 "In2.Cu" signal "IN1")
		(8 "In3.Cu" signal "GND1")
		(10 "In4.Cu" signal "IN2")
		(12 "In5.Cu" signal "GND2")
		(14 "In6.Cu" signal "IN3")
		(16 "In7.Cu" signal "GND3")
		(18 "In8.Cu" signal "VCC")
		(20 "In9.Cu" signal "VCC1")
		(22 "In10.Cu" signal "GND4")
		(24 "In11.Cu" signal "IN4")
		(26 "In12.Cu" signal "GND5")
		(28 "In13.Cu" signal "IN5")
		(30 "In14.Cu" signal "GND6")
		(32 "In15.Cu" signal "IN6")
		(34 "In16.Cu" signal "GND7")
		(2 "B.Cu" signal "BOTTOM")
		(9 "F.Adhes" user "F.Adhesive")
		(11 "B.Adhes" user "B.Adhesive")
		(13 "F.Paste" user "Package Geometry/Pastemask Top")
		(15 "B.Paste" user "Package Geometry/Pastemask Bottom")
		(5 "F.SilkS" user "Ref Des/Silkscreen Top")
		(7 "B.SilkS" user "Ref Des/Silkscreen Bottom")
		(1 "F.Mask" user "Board Geometry/Soldermask Top")
		(3 "B.Mask" user "Board Geometry/Soldermask Bottom")
		(17 "Dwgs.User" user "User.Drawings")
		(19 "Cmts.User" user "User.Comments")
		(21 "Eco1.User" user "User.Eco1")
		(23 "Eco2.User" user "User.Eco2")
		(25 "Edge.Cuts" user "Board Geometry/Outline")
		(27 "Margin" user)
		(31 "F.CrtYd" user "Package Geometry/Place Bound Top")
		(29 "B.CrtYd" user "Package Geometry/Place Bound Bottom")
		(35 "F.Fab" user "Ref Des/Assembly Top")
		(33 "B.Fab" user "Ref Des/Assembly Bottom")
	)
	(footprint ""
		(layer "B.Cu")
		(at 346.497148 -31.527242 180)
		(property "Reference" "R2348"
			(at 0 0 0)
			(layer "B.SilkS")
			(hide yes)
			(effects
				(font
					(size 1.27 1.27)
				)
				(justify mirror)
			)
		)
		(property "Value" ""
			(at 0 0 0)
			(layer "B.Fab")
			(effects
				(font
					(size 1.27 1.27)
				)
				(justify mirror)
			)
		)
		(duplicate_pad_numbers_are_jumpers no)
		(fp_line
			(start 0.7874 0.4064)
			(end 0.7874 -0.4064)
			(stroke
				(width 0.1524)
				(type default)
			)
			(layer "B.SilkS")
		)
		(fp_line
			(start 0.7874 -0.4064)
			(end -0.7874 -0.4064)
			(stroke
				(width 0.1524)
				(type default)
			)
			(layer "B.SilkS")
		)
		(fp_line
			(start -0.7874 0.4064)
			(end 0.7874 0.4064)
			(stroke
				(width 0.1524)
				(type default)
			)
			(layer "B.SilkS")
		)
		(fp_line
			(start -0.7874 -0.4064)
			(end -0.7874 0.4064)
			(stroke
				(width 0.1524)
				(type default)
			)
			(layer "B.SilkS")
		)
		(fp_line
			(start 0.67945 0.3048)
			(end 0.67945 -0.305054)
			(stroke
				(width 0.1)
				(type default)
			)
			(layer "B.Fab")
		)
		(fp_line
			(start 0.67945 -0.305054)
			(end 0.12065 -0.305054)
			(stroke
				(width 0.1)
				(type default)
			)
			(layer "B.Fab")
		)
		(fp_line
			(start 0.12065 0.3048)
			(end 0.67945 0.3048)
			(stroke
				(width 0.1)
				(type default)
			)
			(layer "B.Fab")
		)
		(fp_line
			(start 0.12065 0.2794)
			(end 0.12065 0.3048)
			(stroke
				(width 0.1)
				(type default)
			)
			(layer "B.Fab")
		)
		(fp_line
			(start 0.12065 -0.2794)
			(end -0.12065 -0.2794)
			(stroke
				(width 0.1)
				(type default)
			)
			(layer "B.Fab")
		)
		(fp_line
			(start 0.12065 -0.305054)
			(end 0.12065 -0.2794)
			(stroke
				(width 0.1)
				(type default)
			)
			(layer "B.Fab")
		)
		(fp_line
			(start -0.120396 0.3048)
			(end -0.120396 0.2794)
			(stroke
				(width 0.1)
				(type default)
			)
			(layer "B.Fab")
		)
		(fp_line
			(start -0.120396 0.2794)
			(end 0.12065 0.2794)
			(stroke
				(width 0.1)
				(type default)
			)
			(layer "B.Fab")
		)
		(fp_line
			(start -0.12065 -0.2794)
			(end -0.12065 -0.3048)
			(stroke
				(width 0.1)
				(type default)
			)
			(layer "B.Fab")
		)
		(fp_line
			(start -0.12065 -0.3048)
			(end -0.67945 -0.3048)
			(stroke
				(width 0.1)
				(type default)
			)
			(layer "B.Fab")
		)
		(fp_line
			(start -0.67945 0.3048)
			(end -0.120396 0.3048)
			(stroke
				(width 0.1)
				(type default)
			)
			(layer "B.Fab")
		)
		(fp_line
			(start -0.67945 -0.3048)
			(end -0.67945 0.3048)
			(stroke
				(width 0.1)
				(type default)
			)
			(layer "B.Fab")
		)
		(pad "1" smd circle
			(at 0.40005 0)
			(size 0 0)
			(layers "B.Cu" "B.Mask" "B.Paste")
			(net "FM_DEBUG_PORT_PRSNT_N")
		)
		(pad "2" smd circle
			(at -0.40005 0)
			(size 0 0)
			(layers "B.Cu" "B.Mask" "B.Paste")
			(net "FM_DEBUG_PORT_PRSNT_R_N")
		)
	)
	(footprint ""
		(layer "B.Cu")
		(at 192.724532 -423.657014 -90)
		(property "Reference" "R4703"
			(at 0 0 90)
			(layer "B.SilkS")
			(hide yes)
			(effects
				(font
					(size 1.27 1.27)
				)
				(justify mirror)
			)
		)
		(property "Value" ""
			(at 0 0 90)
			(layer "B.Fab")
			(effects
				(font
					(size 1.27 1.27)
				)
				(justify mirror)
			)
		)
		(duplicate_pad_numbers_are_jumpers no)
		(fp_line
			(start -0.7874 0.4064)
			(end 0.7874 0.4064)
			(stroke
				(width 0.1524)
				(type default)
			)
			(layer "B.SilkS")
		)
		(fp_line
			(start 0.7874 0.4064)
			(end 0.7874 -0.4064)
			(stroke
				(width 0.1524)
				(type default)
			)
			(layer "B.SilkS")
		)
		(fp_line
			(start -0.7874 -0.4064)
			(end -0.7874 0.4064)
			(stroke
				(width 0.1524)
				(type default)
			)
			(layer "B.SilkS")
		)
		(fp_line
			(start 0.7874 -0.4064)
			(end -0.7874 -0.4064)
			(stroke
				(width 0.1524)
				(type default)
			)
			(layer "B.SilkS")
		)
		(fp_line
			(start -0.67945 0.3048)
			(end -0.120396 0.3048)
			(stroke
				(width 0.1)
				(type default)
			)
			(layer "B.Fab")
		)
		(fp_line
			(start -0.120396 0.3048)
			(end -0.120396 0.2794)
			(stroke
				(width 0.1)
				(type default)
			)
			(layer "B.Fab")
		)
		(fp_line
			(start 0.12065 0.3048)
			(end 0.67945 0.3048)
			(stroke
				(width 0.1)
				(type default)
			)
			(layer "B.Fab")
		)
		(fp_line
			(start 0.67945 0.3048)
			(end 0.67945 -0.305054)
			(stroke
				(width 0.1)
				(type default)
			)
			(layer "B.Fab")
		)
		(fp_line
			(start -0.120396 0.2794)
			(end 0.12065 0.2794)
			(stroke
				(width 0.1)
				(type default)
			)
			(layer "B.Fab")
		)
		(fp_line
			(start 0.12065 0.2794)
			(end 0.12065 0.3048)
			(stroke
				(width 0.1)
				(type default)
			)
			(layer "B.Fab")
		)
		(fp_line
			(start -0.12065 -0.2794)
			(end -0.12065 -0.3048)
			(stroke
				(width 0.1)
				(type default)
			)
			(layer "B.Fab")
		)
		(fp_line
			(start 0.12065 -0.2794)
			(end -0.12065 -0.2794)
			(stroke
				(width 0.1)
				(type default)
			)
			(layer "B.Fab")
		)
		(fp_line
			(start -0.67945 -0.3048)
			(end -0.67945 0.3048)
			(stroke
				(width 0.1)
				(type default)
			)
			(layer "B.Fab")
		)
		(fp_line
			(start -0.12065 -0.3048)
			(end -0.67945 -0.3048)
			(stroke
				(width 0.1)
				(type default)
			)
			(layer "B.Fab")
		)
		(fp_line
			(start 0.12065 -0.305054)
			(end 0.12065 -0.2794)
			(stroke
				(width 0.1)
				(type default)
			)
			(layer "B.Fab")
		)
		(fp_line
			(start 0.67945 -0.305054)
			(end 0.12065 -0.305054)
			(stroke
				(width 0.1)
				(type default)
			)
			(layer "B.Fab")
		)
		(pad "1" smd circle
			(at 0.40005 0 90)
			(size 0 0)
			(layers "B.Cu" "B.Mask" "B.Paste")
			(net "LED_P12V_PSU_R1")
		)
		(pad "2" smd circle
			(at -0.40005 0 90)
			(size 0 0)
			(layers "B.Cu" "B.Mask" "B.Paste")
			(net "LED_P12V_PSU_R2")
		)
	)
	(footprint ""
		(layer "B.Cu")
		(at 386.861812 -342.936576 90)
		(property "Reference" "PC240_P0_8"
			(at 0 0 90)
			(layer "B.SilkS")
			(hide yes)
			(effects
				(font
					(size 1.27 1.27)
				)
				(justify mirror)
			)
		)
		(property "Value" ""
			(at 0 0 90)
			(layer "B.Fab")
			(effects
				(font
					(size 1.27 1.27)
				)
				(justify mirror)
			)
		)
		(duplicate_pad_numbers_are_jumpers no)
		(fp_line
			(start 1.524 -0.762)
			(end -1.524 -0.762)
			(stroke
				(width 0.1524)
				(type default)
			)
			(layer "B.SilkS")
		)
		(fp_line
			(start -1.524 -0.762)
			(end -1.524 0.762)
			(stroke
				(width 0.1524)
				(type default)
			)
			(layer "B.SilkS")
		)
		(fp_line
			(start 1.524 0.762)
			(end 1.524 -0.762)
			(stroke
				(width 0.1524)
				(type default)
			)
			(layer "B.SilkS")
		)
		(fp_line
			(start -1.524 0.762)
			(end 1.524 0.762)
			(stroke
				(width 0.1524)
				(type default)
			)
			(layer "B.SilkS")
		)
		(fp_line
			(start 1.1049 -0.724916)
			(end 1.1049 0.724916)
			(stroke
				(width 0.1)
				(type default)
			)
			(layer "B.Fab")
		)
		(fp_line
			(start -1.1049 -0.724916)
			(end 1.1049 -0.724916)
			(stroke
				(width 0.1)
				(type default)
			)
			(layer "B.Fab")
		)
		(fp_line
			(start 1.1049 0.724916)
			(end -1.1049 0.724916)
			(stroke
				(width 0.1)
				(type default)
			)
			(layer "B.Fab")
		)
		(fp_line
			(start -1.1049 0.724916)
			(end -1.1049 -0.724916)
			(stroke
				(width 0.1)
				(type default)
			)
			(layer "B.Fab")
		)
		(pad "1" smd rect
			(at 0.889 0 90)
			(size 1.016 1.27)
			(layers "B.Cu" "B.Mask" "B.Paste")
			(net "SW_P12V_PVCCIN_CPU0_FLT")
		)
		(pad "2" smd rect
			(at -0.889 0 90)
			(size 1.016 1.27)
			(layers "B.Cu" "B.Mask" "B.Paste")
			(net "GND")
		)
	)
)
